(kicad_pcb
	(version 20260206)
	(generator "pcbnew")
	(generator_version "10.0")
	(general
		(thickness 1.6)
		(legacy_teardrops no)
	)
	(paper "A4")
	(title_block
		(title "01162023_DA0F0TEBIF0_F0T_Expander_BD_F_brd_V02_OCP.brd")
		(comment 1 "Grand Teton / footprints 9655-9661 of 9728")
	)
	(layers
		(0 "F.Cu" signal "TOP")
		(4 "In1.Cu" signal "GND")
		(6 "In2.Cu" signal "VCC")
		(8 "In3.Cu" signal "VCC1")
		(10 "In4.Cu" signal "GND1")
		(12 "In5.Cu" signal "IN1")
		(14 "In6.Cu" signal "GND2")
		(16 "In7.Cu" signal "IN2")
		(18 "In8.Cu" signal "GND3")
		(20 "In9.Cu" signal "IN3")
		(22 "In10.Cu" signal "GND4")
		(24 "In11.Cu" signal "IN4")
		(26 "In12.Cu" signal "GND5")
		(28 "In13.Cu" signal "IN5")
		(30 "In14.Cu" signal "GND6")
		(32 "In15.Cu" signal "IN6")
		(34 "In16.Cu" signal "GND7")
		(2 "B.Cu" signal "BOTTOM")
		(9 "F.Adhes" user "F.Adhesive")
		(11 "B.Adhes" user "B.Adhesive")
		(13 "F.Paste" user "Package Geometry/Pastemask Top")
		(15 "B.Paste" user "Package Geometry/Pastemask Bottom")
		(5 "F.SilkS" user "Ref Des/Silkscreen Top")
		(7 "B.SilkS" user "Ref Des/Silkscreen Bottom")
		(1 "F.Mask" user "Board Geometry/Soldermask Top")
		(3 "B.Mask" user "Board Geometry/Soldermask Bottom")
		(17 "Dwgs.User" user "User.Drawings")
		(19 "Cmts.User" user "User.Comments")
		(21 "Eco1.User" user "User.Eco1")
		(23 "Eco2.User" user "User.Eco2")
		(25 "Edge.Cuts" user "Board Geometry/Outline")
		(27 "Margin" user)
		(31 "F.CrtYd" user "Package Geometry/Place Bound Top")
		(29 "B.CrtYd" user "Package Geometry/Place Bound Bottom")
		(35 "F.Fab" user "Ref Des/Assembly Top")
		(33 "B.Fab" user "Ref Des/Assembly Bottom")
	)
	(footprint ""
		(layer "B.Cu")
		(at 213.935056 -215.272874)
		(property "Reference" "R6414"
			(at 0 0 0)
			(layer "B.SilkS")
			(hide yes)
			(effects
				(font
					(size 1.27 1.27)
				)
				(justify mirror)
			)
		)
		(property "Value" ""
			(at 0 0 0)
			(layer "B.Fab")
			(effects
				(font
					(size 1.27 1.27)
				)
				(justify mirror)
			)
		)
		(duplicate_pad_numbers_are_jumpers no)
		(fp_line
			(start -0.7874 -0.4064)
			(end -0.7874 0.4064)
			(stroke
				(width 0.1524)
				(type default)
			)
			(layer "B.SilkS")
		)
		(fp_line
			(start -0.7874 0.4064)
			(end 0.7874 0.4064)
			(stroke
				(width 0.1524)
				(type default)
			)
			(layer "B.SilkS")
		)
		(fp_line
			(start 0.7874 -0.4064)
			(end -0.7874 -0.4064)
			(stroke
				(width 0.1524)
				(type default)
			)
			(layer "B.SilkS")
		)
		(fp_line
			(start 0.7874 0.4064)
			(end 0.7874 -0.4064)
			(stroke
				(width 0.1524)
				(type default)
			)
			(layer "B.SilkS")
		)
		(fp_line
			(start -0.67945 -0.3048)
			(end -0.67945 0.3048)
			(stroke
				(width 0.1)
				(type default)
			)
			(layer "B.Fab")
		)
		(fp_line
			(start -0.67945 0.3048)
			(end -0.120396 0.3048)
			(stroke
				(width 0.1)
				(type default)
			)
			(layer "B.Fab")
		)
		(fp_line
			(start -0.12065 -0.3048)
			(end -0.67945 -0.3048)
			(stroke
				(width 0.1)
				(type default)
			)
			(layer "B.Fab")
		)
		(fp_line
			(start -0.12065 -0.2794)
			(end -0.12065 -0.3048)
			(stroke
				(width 0.1)
				(type default)
			)
			(layer "B.Fab")
		)
		(fp_line
			(start -0.120396 0.2794)
			(end 0.12065 0.2794)
			(stroke
				(width 0.1)
				(type default)
			)
			(layer "B.Fab")
		)
		(fp_line
			(start -0.120396 0.3048)
			(end -0.120396 0.2794)
			(stroke
				(width 0.1)
				(type default)
			)
			(layer "B.Fab")
		)
		(fp_line
			(start 0.12065 -0.305054)
			(end 0.12065 -0.2794)
			(stroke
				(width 0.1)
				(type default)
			)
			(layer "B.Fab")
		)
		(fp_line
			(start 0.12065 -0.2794)
			(end -0.12065 -0.2794)
			(stroke
				(width 0.1)
				(type default)
			)
			(layer "B.Fab")
		)
		(fp_line
			(start 0.12065 0.2794)
			(end 0.12065 0.3048)
			(stroke
				(width 0.1)
				(type default)
			)
			(layer "B.Fab")
		)
		(fp_line
			(start 0.12065 0.3048)
			(end 0.67945 0.3048)
			(stroke
				(width 0.1)
				(type default)
			)
			(layer "B.Fab")
		)
		(fp_line
			(start 0.67945 -0.305054)
			(end 0.12065 -0.305054)
			(stroke
				(width 0.1)
				(type default)
			)
			(layer "B.Fab")
		)
		(fp_line
			(start 0.67945 0.3048)
			(end 0.67945 -0.305054)
			(stroke
				(width 0.1)
				(type default)
			)
			(layer "B.Fab")
		)
		(pad "1" smd circle
			(at 0.40005 0 180)
			(size 0 0)
			(layers "B.Cu" "B.Mask" "B.Paste")
			(net "RST_BIC_I2C6_MUX_N")
		)
		(pad "2" smd circle
			(at -0.40005 0 180)
			(size 0 0)
			(layers "B.Cu" "B.Mask" "B.Paste")
			(net "P3V3_AUX")
		)
	)
	(footprint ""
		(layer "B.Cu")
		(at 342.011 -207.772 90)
		(property "Reference" "R4141"
			(at 0 0 90)
			(layer "B.SilkS")
			(hide yes)
			(effects
				(font
					(size 1.27 1.27)
				)
				(justify mirror)
			)
		)
		(property "Value" ""
			(at 0 0 90)
			(layer "B.Fab")
			(effects
				(font
					(size 1.27 1.27)
				)
				(justify mirror)
			)
		)
		(duplicate_pad_numbers_are_jumpers no)
		(fp_line
			(start 0.7874 -0.4064)
			(end -0.7874 -0.4064)
			(stroke
				(width 0.1524)
				(type default)
			)
			(layer "B.SilkS")
		)
		(fp_line
			(start -0.7874 -0.4064)
			(end -0.7874 0.4064)
			(stroke
				(width 0.1524)
				(type default)
			)
			(layer "B.SilkS")
		)
		(fp_line
			(start 0.7874 0.4064)
			(end 0.7874 -0.4064)
			(stroke
				(width 0.1524)
				(type default)
			)
			(layer "B.SilkS")
		)
		(fp_line
			(start -0.7874 0.4064)
			(end 0.7874 0.4064)
			(stroke
				(width 0.1524)
				(type default)
			)
			(layer "B.SilkS")
		)
		(fp_line
			(start 0.67945 -0.305054)
			(end 0.12065 -0.305054)
			(stroke
				(width 0.1)
				(type default)
			)
			(layer "B.Fab")
		)
		(fp_line
			(start 0.12065 -0.305054)
			(end 0.12065 -0.2794)
			(stroke
				(width 0.1)
				(type default)
			)
			(layer "B.Fab")
		)
		(fp_line
			(start -0.12065 -0.3048)
			(end -0.67945 -0.3048)
			(stroke
				(width 0.1)
				(type default)
			)
			(layer "B.Fab")
		)
		(fp_line
			(start -0.67945 -0.3048)
			(end -0.67945 0.3048)
			(stroke
				(width 0.1)
				(type default)
			)
			(layer "B.Fab")
		)
		(fp_line
			(start 0.12065 -0.2794)
			(end -0.12065 -0.2794)
			(stroke
				(width 0.1)
				(type default)
			)
			(layer "B.Fab")
		)
		(fp_line
			(start -0.12065 -0.2794)
			(end -0.12065 -0.3048)
			(stroke
				(width 0.1)
				(type default)
			)
			(layer "B.Fab")
		)
		(fp_line
			(start 0.12065 0.2794)
			(end 0.12065 0.3048)
			(stroke
				(width 0.1)
				(type default)
			)
			(layer "B.Fab")
		)
		(fp_line
			(start -0.120396 0.2794)
			(end 0.12065 0.2794)
			(stroke
				(width 0.1)
				(type default)
			)
			(layer "B.Fab")
		)
		(fp_line
			(start 0.67945 0.3048)
			(end 0.67945 -0.305054)
			(stroke
				(width 0.1)
				(type default)
			)
			(layer "B.Fab")
		)
		(fp_line
			(start 0.12065 0.3048)
			(end 0.67945 0.3048)
			(stroke
				(width 0.1)
				(type default)
			)
			(layer "B.Fab")
		)
		(fp_line
			(start -0.120396 0.3048)
			(end -0.120396 0.2794)
			(stroke
				(width 0.1)
				(type default)
			)
			(layer "B.Fab")
		)
		(fp_line
			(start -0.67945 0.3048)
			(end -0.120396 0.3048)
			(stroke
				(width 0.1)
				(type default)
			)
			(layer "B.Fab")
		)
		(pad "1" smd circle
			(at 0.40005 0 270)
			(size 0 0)
			(layers "B.Cu" "B.Mask" "B.Paste")
			(net "RST_SSD14_PERST_N")
		)
		(pad "2" smd circle
			(at -0.40005 0 270)
			(size 0 0)
			(layers "B.Cu" "B.Mask" "B.Paste")
			(net "RST_SSD14_PERST_R_N")
		)
	)
	(footprint ""
		(layer "B.Cu")
		(at 396.0749 -292.84168 90)
		(property "Reference" "C3568"
			(at 0 0 90)
			(layer "B.SilkS")
			(hide yes)
			(effects
				(font
					(size 1.27 1.27)
				)
				(justify mirror)
			)
		)
		(property "Value" ""
			(at 0 0 90)
			(layer "B.Fab")
			(effects
				(font
					(size 1.27 1.27)
				)
				(justify mirror)
			)
		)
		(duplicate_pad_numbers_are_jumpers no)
		(fp_line
			(start 0.299974 -0.150114)
			(end -0.299974 -0.150114)
			(stroke
				(width 0.1)
				(type default)
			)
			(layer "B.Fab")
		)
		(fp_line
			(start -0.299974 -0.150114)
			(end -0.299974 0.150114)
			(stroke
				(width 0.1)
				(type default)
			)
			(layer "B.Fab")
		)
		(fp_line
			(start 0.299974 0.150114)
			(end 0.299974 -0.150114)
			(stroke
				(width 0.1)
				(type default)
			)
			(layer "B.Fab")
		)
		(fp_line
			(start -0.299974 0.150114)
			(end 0.299974 0.150114)
			(stroke
				(width 0.1)
				(type default)
			)
			(layer "B.Fab")
		)
		(pad "1" smd rect
			(at 0.2667 0 270)
			(size 0.3048 0.381)
			(layers "B.Cu" "B.Mask" "B.Paste")
			(net "PCEPLL5_VDDA18_PEX3")
		)
		(pad "2" smd rect
			(at -0.2667 0 270)
			(size 0.3048 0.381)
			(layers "B.Cu" "B.Mask" "B.Paste")
			(net "GND")
		)
	)
	(footprint ""
		(layer "B.Cu")
		(at 162.226244 -140.8176 180)
		(property "Reference" "C884"
			(at 0 0 0)
			(layer "B.SilkS")
			(hide yes)
			(effects
				(font
					(size 1.27 1.27)
				)
				(justify mirror)
			)
		)
		(property "Value" ""
			(at 0 0 0)
			(layer "B.Fab")
			(effects
				(font
					(size 1.27 1.27)
				)
				(justify mirror)
			)
		)
		(duplicate_pad_numbers_are_jumpers no)
		(fp_line
			(start 0.7874 0.4064)
			(end 0.7874 -0.4064)
			(stroke
				(width 0.1524)
				(type default)
			)
			(layer "B.SilkS")
		)
		(fp_line
			(start 0.7874 -0.4064)
			(end -0.7874 -0.4064)
			(stroke
				(width 0.1524)
				(type default)
			)
			(layer "B.SilkS")
		)
		(fp_line
			(start -0.7874 0.4064)
			(end 0.7874 0.4064)
			(stroke
				(width 0.1524)
				(type default)
			)
			(layer "B.SilkS")
		)
		(fp_line
			(start -0.7874 -0.4064)
			(end -0.7874 0.4064)
			(stroke
				(width 0.1524)
				(type default)
			)
			(layer "B.SilkS")
		)
		(fp_line
			(start 0.67945 0.3048)
			(end 0.67945 -0.305054)
			(stroke
				(width 0.1)
				(type default)
			)
			(layer "B.Fab")
		)
		(fp_line
			(start 0.67945 -0.305054)
			(end 0.12065 -0.305054)
			(stroke
				(width 0.1)
				(type default)
			)
			(layer "B.Fab")
		)
		(fp_line
			(start 0.12065 0.3048)
			(end 0.67945 0.3048)
			(stroke
				(width 0.1)
				(type default)
			)
			(layer "B.Fab")
		)
		(fp_line
			(start 0.12065 0.2794)
			(end 0.12065 0.3048)
			(stroke
				(width 0.1)
				(type default)
			)
			(layer "B.Fab")
		)
		(fp_line
			(start 0.12065 -0.2794)
			(end -0.12065 -0.2794)
			(stroke
				(width 0.1)
				(type default)
			)
			(layer "B.Fab")
		)
		(fp_line
			(start 0.12065 -0.305054)
			(end 0.12065 -0.2794)
			(stroke
				(width 0.1)
				(type default)
			)
			(layer "B.Fab")
		)
		(fp_line
			(start -0.120396 0.3048)
			(end -0.120396 0.2794)
			(stroke
				(width 0.1)
				(type default)
			)
			(layer "B.Fab")
		)
		(fp_line
			(start -0.120396 0.2794)
			(end 0.12065 0.2794)
			(stroke
				(width 0.1)
				(type default)
			)
			(layer "B.Fab")
		)
		(fp_line
			(start -0.12065 -0.2794)
			(end -0.12065 -0.3048)
			(stroke
				(width 0.1)
				(type default)
			)
			(layer "B.Fab")
		)
		(fp_line
			(start -0.12065 -0.3048)
			(end -0.67945 -0.3048)
			(stroke
				(width 0.1)
				(type default)
			)
			(layer "B.Fab")
		)
		(fp_line
			(start -0.67945 0.3048)
			(end -0.120396 0.3048)
			(stroke
				(width 0.1)
				(type default)
			)
			(layer "B.Fab")
		)
		(fp_line
			(start -0.67945 -0.3048)
			(end -0.67945 0.3048)
			(stroke
				(width 0.1)
				(type default)
			)
			(layer "B.Fab")
		)
		(pad "1" smd circle
			(at 0.40005 0)
			(size 0 0)
			(layers "B.Cu" "B.Mask" "B.Paste")
			(net "P3V3_NIC2")
		)
		(pad "2" smd circle
			(at -0.40005 0)
			(size 0 0)
			(layers "B.Cu" "B.Mask" "B.Paste")
			(net "GND")
		)
	)
	(footprint ""
		(layer "B.Cu")
		(at 382.895602 -244.53596)
		(property "Reference" "C2567"
			(at 0 0 0)
			(layer "B.SilkS")
			(hide yes)
			(effects
				(font
					(size 1.27 1.27)
				)
				(justify mirror)
			)
		)
		(property "Value" ""
			(at 0 0 0)
			(layer "B.Fab")
			(effects
				(font
					(size 1.27 1.27)
				)
				(justify mirror)
			)
		)
		(duplicate_pad_numbers_are_jumpers no)
		(fp_line
			(start -0.7874 -0.4064)
			(end -0.7874 0.4064)
			(stroke
				(width 0.1524)
				(type default)
			)
			(layer "B.SilkS")
		)
		(fp_line
			(start -0.7874 0.4064)
			(end 0.7874 0.4064)
			(stroke
				(width 0.1524)
				(type default)
			)
			(layer "B.SilkS")
		)
		(fp_line
			(start 0.7874 -0.4064)
			(end -0.7874 -0.4064)
			(stroke
				(width 0.1524)
				(type default)
			)
			(layer "B.SilkS")
		)
		(fp_line
			(start 0.7874 0.4064)
			(end 0.7874 -0.4064)
			(stroke
				(width 0.1524)
				(type default)
			)
			(layer "B.SilkS")
		)
		(fp_line
			(start -0.67945 -0.3048)
			(end -0.67945 0.3048)
			(stroke
				(width 0.1)
				(type default)
			)
			(layer "B.Fab")
		)
		(fp_line
			(start -0.67945 0.3048)
			(end -0.120396 0.3048)
			(stroke
				(width 0.1)
				(type default)
			)
			(layer "B.Fab")
		)
		(fp_line
			(start -0.12065 -0.3048)
			(end -0.67945 -0.3048)
			(stroke
				(width 0.1)
				(type default)
			)
			(layer "B.Fab")
		)
		(fp_line
			(start -0.12065 -0.2794)
			(end -0.12065 -0.3048)
			(stroke
				(width 0.1)
				(type default)
			)
			(layer "B.Fab")
		)
		(fp_line
			(start -0.120396 0.2794)
			(end 0.12065 0.2794)
			(stroke
				(width 0.1)
				(type default)
			)
			(layer "B.Fab")
		)
		(fp_line
			(start -0.120396 0.3048)
			(end -0.120396 0.2794)
			(stroke
				(width 0.1)
				(type default)
			)
			(layer "B.Fab")
		)
		(fp_line
			(start 0.12065 -0.305054)
			(end 0.12065 -0.2794)
			(stroke
				(width 0.1)
				(type default)
			)
			(layer "B.Fab")
		)
		(fp_line
			(start 0.12065 -0.2794)
			(end -0.12065 -0.2794)
			(stroke
				(width 0.1)
				(type default)
			)
			(layer "B.Fab")
		)
		(fp_line
			(start 0.12065 0.2794)
			(end 0.12065 0.3048)
			(stroke
				(width 0.1)
				(type default)
			)
			(layer "B.Fab")
		)
		(fp_line
			(start 0.12065 0.3048)
			(end 0.67945 0.3048)
			(stroke
				(width 0.1)
				(type default)
			)
			(layer "B.Fab")
		)
		(fp_line
			(start 0.67945 -0.305054)
			(end 0.12065 -0.305054)
			(stroke
				(width 0.1)
				(type default)
			)
			(layer "B.Fab")
		)
		(fp_line
			(start 0.67945 0.3048)
			(end 0.67945 -0.305054)
			(stroke
				(width 0.1)
				(type default)
			)
			(layer "B.Fab")
		)
		(pad "1" smd circle
			(at 0.40005 0 180)
			(size 0 0)
			(layers "B.Cu" "B.Mask" "B.Paste")
			(net "P3V3_AUX")
		)
		(pad "2" smd circle
			(at -0.40005 0 180)
			(size 0 0)
			(layers "B.Cu" "B.Mask" "B.Paste")
			(net "GND")
		)
	)
	(footprint ""
		(layer "B.Cu")
		(at 155.800044 -288.774886 -90)
		(property "Reference" "R3453"
			(at 0 0 90)
			(layer "B.SilkS")
			(hide yes)
			(effects
				(font
					(size 1.27 1.27)
				)
				(justify mirror)
			)
		)
		(property "Value" ""
			(at 0 0 90)
			(layer "B.Fab")
			(effects
				(font
					(size 1.27 1.27)
				)
				(justify mirror)
			)
		)
		(duplicate_pad_numbers_are_jumpers no)
		(fp_line
			(start -0.7874 0.4064)
			(end 0.7874 0.4064)
			(stroke
				(width 0.1524)
				(type default)
			)
			(layer "B.SilkS")
		)
		(fp_line
			(start 0.7874 0.4064)
			(end 0.7874 -0.4064)
			(stroke
				(width 0.1524)
				(type default)
			)
			(layer "B.SilkS")
		)
		(fp_line
			(start -0.7874 -0.4064)
			(end -0.7874 0.4064)
			(stroke
				(width 0.1524)
				(type default)
			)
			(layer "B.SilkS")
		)
		(fp_line
			(start 0.7874 -0.4064)
			(end -0.7874 -0.4064)
			(stroke
				(width 0.1524)
				(type default)
			)
			(layer "B.SilkS")
		)
		(fp_line
			(start -0.67945 0.3048)
			(end -0.120396 0.3048)
			(stroke
				(width 0.1)
				(type default)
			)
			(layer "B.Fab")
		)
		(fp_line
			(start -0.120396 0.3048)
			(end -0.120396 0.2794)
			(stroke
				(width 0.1)
				(type default)
			)
			(layer "B.Fab")
		)
		(fp_line
			(start 0.12065 0.3048)
			(end 0.67945 0.3048)
			(stroke
				(width 0.1)
				(type default)
			)
			(layer "B.Fab")
		)
		(fp_line
			(start 0.67945 0.3048)
			(end 0.67945 -0.305054)
			(stroke
				(width 0.1)
				(type default)
			)
			(layer "B.Fab")
		)
		(fp_line
			(start -0.120396 0.2794)
			(end 0.12065 0.2794)
			(stroke
				(width 0.1)
				(type default)
			)
			(layer "B.Fab")
		)
		(fp_line
			(start 0.12065 0.2794)
			(end 0.12065 0.3048)
			(stroke
				(width 0.1)
				(type default)
			)
			(layer "B.Fab")
		)
		(fp_line
			(start -0.12065 -0.2794)
			(end -0.12065 -0.3048)
			(stroke
				(width 0.1)
				(type default)
			)
			(layer "B.Fab")
		)
		(fp_line
			(start 0.12065 -0.2794)
			(end -0.12065 -0.2794)
			(stroke
				(width 0.1)
				(type default)
			)
			(layer "B.Fab")
		)
		(fp_line
			(start -0.67945 -0.3048)
			(end -0.67945 0.3048)
			(stroke
				(width 0.1)
				(type default)
			)
			(layer "B.Fab")
		)
		(fp_line
			(start -0.12065 -0.3048)
			(end -0.67945 -0.3048)
			(stroke
				(width 0.1)
				(type default)
			)
			(layer "B.Fab")
		)
		(fp_line
			(start 0.12065 -0.305054)
			(end 0.12065 -0.2794)
			(stroke
				(width 0.1)
				(type default)
			)
			(layer "B.Fab")
		)
		(fp_line
			(start 0.67945 -0.305054)
			(end 0.12065 -0.305054)
			(stroke
				(width 0.1)
				(type default)
			)
			(layer "B.Fab")
		)
		(pad "1" smd circle
			(at 0.40005 0 90)
			(size 0 0)
			(layers "B.Cu" "B.Mask" "B.Paste")
			(net "SPI_PEX1_SDIO3_R")
		)
		(pad "2" smd circle
			(at -0.40005 0 90)
			(size 0 0)
			(layers "B.Cu" "B.Mask" "B.Paste")
			(net "SPI_PEX1_SDIO3")
		)
	)
	(footprint ""
		(layer "B.Cu")
		(at 451.298056 -266.996672)
		(property "Reference" "L131"
			(at 0 0 0)
			(layer "B.SilkS")
			(hide yes)
			(effects
				(font
					(size 1.27 1.27)
				)
				(justify mirror)
			)
		)
		(property "Value" ""
			(at 0 0 0)
			(layer "B.Fab")
			(effects
				(font
					(size 1.27 1.27)
				)
				(justify mirror)
			)
		)
		(duplicate_pad_numbers_are_jumpers no)
		(fp_line
			(start -2.248154 -4.9911)
			(end 2.248154 -4.9911)
			(stroke
				(width 0.1524)
				(type default)
			)
			(layer "B.SilkS")
		)
		(fp_line
			(start -2.248154 -1.89865)
			(end -2.248154 -4.9911)
			(stroke
				(width 0.1524)
				(type default)
			)
			(layer "B.SilkS")
		)
		(fp_line
			(start -2.248154 4.9911)
			(end -2.248154 2.293112)
			(stroke
				(width 0.1524)
				(type default)
			)
			(layer "B.SilkS")
		)
		(fp_line
			(start 2.248154 -4.9911)
			(end 2.248154 -1.89865)
			(stroke
				(width 0.1524)
				(type default)
			)
			(layer "B.SilkS")
		)
		(fp_line
			(start 2.248154 2.293112)
			(end 2.248154 4.9911)
			(stroke
				(width 0.1524)
				(type default)
			)
			(layer "B.SilkS")
		)
		(fp_line
			(start 2.248154 4.9911)
			(end -2.248154 4.9911)
			(stroke
				(width 0.1524)
				(type default)
			)
			(layer "B.SilkS")
		)
		(fp_line
			(start -1.700022 -0.899922)
			(end 1.700022 -0.899922)
			(stroke
				(width 0.1)
				(type default)
			)
			(layer "B.Fab")
		)
		(fp_line
			(start -1.700022 0.899922)
			(end -1.700022 -0.899922)
			(stroke
				(width 0.1)
				(type default)
			)
			(layer "B.Fab")
		)
		(fp_line
			(start 1.700022 -0.899922)
			(end 1.700022 0.899922)
			(stroke
				(width 0.1)
				(type default)
			)
			(layer "B.Fab")
		)
		(fp_line
			(start 1.700022 0.899922)
			(end -1.700022 0.899922)
			(stroke
				(width 0.1)
				(type default)
			)
			(layer "B.Fab")
		)
		(pad "1" smd rect
			(at 1.575054 0 180)
			(size 1.1684 9.8044)
			(layers "B.Cu" "B.Mask" "B.Paste")
			(net "P1V25_PEX3")
		)
		(pad "2" smd rect
			(at -1.575054 0 180)
			(size 1.1684 9.8044)
			(layers "B.Cu" "B.Mask" "B.Paste")
			(net "P1V25_SERDES_VDDPLL_PEX3")
		)
	)
)
